(kicad_pcb
	(version 20260206)
	(generator "pcbnew")
	(generator_version "10.0")
	(general
		(thickness 1.6)
		(legacy_teardrops no)
	)
	(paper "A4")
	(title_block
		(title "Bryce Canyon_F.DPB_16315-1-OCP.brd")
		(comment 1 "Bryce Canyon / footprints 195-201 of 2223")
	)
	(layers
		(0 "F.Cu" signal "TOP")
		(4 "In1.Cu" signal "L2GND")
		(6 "In2.Cu" signal "L3")
		(8 "In3.Cu" signal "L4GND")
		(10 "In4.Cu" signal "L5")
		(12 "In5.Cu" signal "L6VCC")
		(14 "In6.Cu" signal "L7VCC")
		(16 "In7.Cu" signal "L8")
		(18 "In8.Cu" signal "L9GND")
		(20 "In9.Cu" signal "L10")
		(22 "In10.Cu" signal "L11GND")
		(2 "B.Cu" signal "BOTTOM")
		(9 "F.Adhes" user "F.Adhesive")
		(11 "B.Adhes" user "B.Adhesive")
		(13 "F.Paste" user "Package Geometry/Pastemask Top")
		(15 "B.Paste" user "Package Geometry/Pastemask Bottom")
		(5 "F.SilkS" user "Ref Des/Silkscreen Top")
		(7 "B.SilkS" user "Ref Des/Silkscreen Bottom")
		(1 "F.Mask" user "Board Geometry/Soldermask Top")
		(3 "B.Mask" user "Board Geometry/Soldermask Bottom")
		(17 "Dwgs.User" user "User.Drawings")
		(19 "Cmts.User" user "User.Comments")
		(21 "Eco1.User" user "User.Eco1")
		(23 "Eco2.User" user "User.Eco2")
		(25 "Edge.Cuts" user "Board Geometry/Outline")
		(27 "Margin" user)
		(31 "F.CrtYd" user "Package Geometry/Place Bound Top")
		(29 "B.CrtYd" user "Package Geometry/Place Bound Bottom")
		(35 "F.Fab" user "Ref Des/Assembly Top")
		(33 "B.Fab" user "Ref Des/Assembly Bottom")
	)
	(footprint ""
		(layer "F.Cu")
		(at 70.17258 -181.381146 90)
		(property "Reference" "R458"
			(at 0 0 90)
			(layer "F.SilkS")
			(hide yes)
			(effects
				(font
					(size 1.27 1.27)
				)
			)
		)
		(property "Value" "4K7R2J-2-GP"
			(at 0.064008 -3.993896 90)
			(unlocked yes)
			(layer "F.Fab")
			(hide yes)
			(effects
				(font
					(size 1.016 1.016)
					(thickness 0.1524)
				)
			)
		)
		(property "Device Type" "R402H16"
			(at 0.064008 -5.517896 90)
			(unlocked yes)
			(layer "F.Fab")
			(hide yes)
			(effects
				(font
					(size 1.016 1.016)
					(thickness 0.1524)
				)
			)
		)
		(duplicate_pad_numbers_are_jumpers no)
		(fp_line
			(start 0.508 -0.9398)
			(end -0.508 -0.9398)
			(stroke
				(width 0.1524)
				(type default)
			)
			(layer "F.SilkS")
		)
		(fp_line
			(start -0.508 -0.9398)
			(end -0.508 0.9398)
			(stroke
				(width 0.1524)
				(type default)
			)
			(layer "F.SilkS")
		)
		(fp_rect
			(start -0.508 0.9398)
			(end 0.508 -0.9398)
			(stroke
				(width 0)
				(type default)
			)
			(fill no)
			(layer "F.CrtYd")
		)
		(fp_rect
			(start -0.508 0.9398)
			(end 0.508 -0.9398)
			(stroke
				(width 0)
				(type default)
			)
			(fill no)
			(layer "F.Fab")
		)
		(pad "1" smd custom
			(at 0 -0.4445 90)
			(size 0.1397 0.1397)
			(layers "F.Cu" "F.Mask" "F.Paste")
			(net "DRIVE_A_2_ACT")
			(options
				(clearance outline)
				(anchor circle)
			)
			(primitives
				(gr_poly
					(pts
						(arc
							(start -0.1778 -0.2794)
							(mid -0.249642 -0.249642)
							(end -0.2794 -0.1778)
						)
						(arc
							(start -0.2794 0.1778)
							(mid -0.249642 0.249642)
							(end -0.1778 0.2794)
						)
						(arc
							(start 0.1778 0.2794)
							(mid 0.249642 0.249642)
							(end 0.2794 0.1778)
						)
						(arc
							(start 0.2794 -0.1778)
							(mid 0.249642 -0.249642)
							(end 0.1778 -0.2794)
						)
					)
					(width 0)
					(fill yes)
				)
			)
		)
		(pad "2" smd custom
			(at 0 0.4445 90)
			(size 0.1397 0.1397)
			(layers "F.Cu" "F.Mask" "F.Paste")
			(net "GND")
			(options
				(clearance outline)
				(anchor circle)
			)
			(primitives
				(gr_poly
					(pts
						(arc
							(start -0.1778 -0.2794)
							(mid -0.249642 -0.249642)
							(end -0.2794 -0.1778)
						)
						(arc
							(start -0.2794 0.1778)
							(mid -0.249642 0.249642)
							(end -0.1778 0.2794)
						)
						(arc
							(start 0.1778 0.2794)
							(mid 0.249642 0.249642)
							(end 0.2794 0.1778)
						)
						(arc
							(start 0.2794 -0.1778)
							(mid 0.249642 -0.249642)
							(end 0.1778 -0.2794)
						)
					)
					(width 0)
					(fill yes)
				)
			)
		)
	)
	(footprint ""
		(layer "F.Cu")
		(at 463.1309 -45.735494 180)
		(property "Reference" "R927"
			(at 0 0 180)
			(layer "F.SilkS")
			(hide yes)
			(effects
				(font
					(size 1.27 1.27)
				)
			)
		)
		(property "Value" "4K7R2J-2-GP"
			(at 0.064008 -3.993896 180)
			(unlocked yes)
			(layer "F.Fab")
			(hide yes)
			(effects
				(font
					(size 1.016 1.016)
					(thickness 0.1524)
				)
			)
		)
		(property "Device Type" "R402H16"
			(at 0.064008 -5.517896 180)
			(unlocked yes)
			(layer "F.Fab")
			(hide yes)
			(effects
				(font
					(size 1.016 1.016)
					(thickness 0.1524)
				)
			)
		)
		(duplicate_pad_numbers_are_jumpers no)
		(fp_line
			(start 0.508 -0.9398)
			(end -0.508 -0.9398)
			(stroke
				(width 0.1524)
				(type default)
			)
			(layer "F.SilkS")
		)
		(fp_line
			(start -0.508 -0.9398)
			(end -0.508 0.9398)
			(stroke
				(width 0.1524)
				(type default)
			)
			(layer "F.SilkS")
		)
		(fp_rect
			(start -0.508 0.9398)
			(end 0.508 -0.9398)
			(stroke
				(width 0)
				(type default)
			)
			(fill no)
			(layer "F.CrtYd")
		)
		(fp_rect
			(start -0.508 0.9398)
			(end 0.508 -0.9398)
			(stroke
				(width 0)
				(type default)
			)
			(fill no)
			(layer "F.Fab")
		)
		(pad "1" smd custom
			(at 0 -0.4445 180)
			(size 0.1397 0.1397)
			(layers "F.Cu" "F.Mask" "F.Paste")
			(net "P12V_A")
			(options
				(clearance outline)
				(anchor circle)
			)
			(primitives
				(gr_poly
					(pts
						(arc
							(start -0.1778 -0.2794)
							(mid -0.249642 -0.249642)
							(end -0.2794 -0.1778)
						)
						(arc
							(start -0.2794 0.1778)
							(mid -0.249642 0.249642)
							(end -0.1778 0.2794)
						)
						(arc
							(start 0.1778 0.2794)
							(mid 0.249642 0.249642)
							(end 0.2794 0.1778)
						)
						(arc
							(start 0.2794 -0.1778)
							(mid 0.249642 -0.249642)
							(end 0.1778 -0.2794)
						)
					)
					(width 0)
					(fill yes)
				)
			)
		)
		(pad "2" smd custom
			(at 0 0.4445 180)
			(size 0.1397 0.1397)
			(layers "F.Cu" "F.Mask" "F.Paste")
			(net "SW_HDD_R34")
			(options
				(clearance outline)
				(anchor circle)
			)
			(primitives
				(gr_poly
					(pts
						(arc
							(start -0.1778 -0.2794)
							(mid -0.249642 -0.249642)
							(end -0.2794 -0.1778)
						)
						(arc
							(start -0.2794 0.1778)
							(mid -0.249642 0.249642)
							(end -0.1778 0.2794)
						)
						(arc
							(start 0.1778 0.2794)
							(mid 0.249642 0.249642)
							(end 0.2794 0.1778)
						)
						(arc
							(start 0.2794 -0.1778)
							(mid 0.249642 -0.249642)
							(end 0.1778 -0.2794)
						)
					)
					(width 0)
					(fill yes)
				)
			)
		)
	)
	(footprint ""
		(layer "F.Cu")
		(at 361.180126 -131.764278)
		(property "Reference" "R1099"
			(at 0 0 0)
			(layer "F.SilkS")
			(hide yes)
			(effects
				(font
					(size 1.27 1.27)
				)
			)
		)
		(property "Value" "3K92R2F-GP"
			(at 0.064008 -3.993896 0)
			(unlocked yes)
			(layer "F.Fab")
			(hide yes)
			(effects
				(font
					(size 1.016 1.016)
					(thickness 0.1524)
				)
			)
		)
		(property "Device Type" "R402H16"
			(at 0.064008 -5.517896 0)
			(unlocked yes)
			(layer "F.Fab")
			(hide yes)
			(effects
				(font
					(size 1.016 1.016)
					(thickness 0.1524)
				)
			)
		)
		(duplicate_pad_numbers_are_jumpers no)
		(fp_line
			(start -0.508 -0.9398)
			(end -0.508 0.9398)
			(stroke
				(width 0.1524)
				(type default)
			)
			(layer "F.SilkS")
		)
		(fp_line
			(start 0.508 -0.9398)
			(end -0.508 -0.9398)
			(stroke
				(width 0.1524)
				(type default)
			)
			(layer "F.SilkS")
		)
		(fp_rect
			(start -0.508 0.9398)
			(end 0.508 -0.9398)
			(stroke
				(width 0)
				(type default)
			)
			(fill no)
			(layer "F.CrtYd")
		)
		(fp_rect
			(start -0.508 0.9398)
			(end 0.508 -0.9398)
			(stroke
				(width 0)
				(type default)
			)
			(fill no)
			(layer "F.Fab")
		)
		(pad "1" smd custom
			(at 0 -0.4445)
			(size 0.1397 0.1397)
			(layers "F.Cu" "F.Mask" "F.Paste")
			(net "MB1_CM_OV_R")
			(options
				(clearance outline)
				(anchor circle)
			)
			(primitives
				(gr_poly
					(pts
						(arc
							(start -0.1778 -0.2794)
							(mid -0.249642 -0.249642)
							(end -0.2794 -0.1778)
						)
						(arc
							(start -0.2794 0.1778)
							(mid -0.249642 0.249642)
							(end -0.1778 0.2794)
						)
						(arc
							(start 0.1778 0.2794)
							(mid 0.249642 0.249642)
							(end 0.2794 0.1778)
						)
						(arc
							(start 0.2794 -0.1778)
							(mid 0.249642 -0.249642)
							(end 0.1778 -0.2794)
						)
					)
					(width 0)
					(fill yes)
				)
			)
		)
		(pad "2" smd custom
			(at 0 0.4445)
			(size 0.1397 0.1397)
			(layers "F.Cu" "F.Mask" "F.Paste")
			(net "AGND_CURRENT_MONOB")
			(options
				(clearance outline)
				(anchor circle)
			)
			(primitives
				(gr_poly
					(pts
						(arc
							(start -0.1778 -0.2794)
							(mid -0.249642 -0.249642)
							(end -0.2794 -0.1778)
						)
						(arc
							(start -0.2794 0.1778)
							(mid -0.249642 0.249642)
							(end -0.1778 0.2794)
						)
						(arc
							(start 0.1778 0.2794)
							(mid 0.249642 0.249642)
							(end 0.2794 0.1778)
						)
						(arc
							(start 0.2794 -0.1778)
							(mid 0.249642 -0.249642)
							(end 0.1778 -0.2794)
						)
					)
					(width 0)
					(fill yes)
				)
			)
		)
	)
	(footprint ""
		(layer "F.Cu")
		(at 158.663386 -43.660568 90)
		(property "Reference" "C403"
			(at 0 0 90)
			(layer "F.SilkS")
			(hide yes)
			(effects
				(font
					(size 1.27 1.27)
				)
			)
		)
		(property "Value" "SCD01U16V1KX-GP"
			(at -2.8321 -1.7399 90)
			(unlocked yes)
			(layer "F.Fab")
			(hide yes)
			(effects
				(font
					(size 1.016 1.016)
					(thickness 0.1524)
				)
			)
		)
		(property "Device Type" "C0201H13"
			(at -2.8321 -3.2639 90)
			(unlocked yes)
			(layer "F.Fab")
			(hide yes)
			(effects
				(font
					(size 1.016 1.016)
					(thickness 0.1524)
				)
			)
		)
		(duplicate_pad_numbers_are_jumpers no)
		(fp_rect
			(start -0.2794 0.6477)
			(end 0.2794 -0.6477)
			(stroke
				(width 0)
				(type default)
			)
			(fill no)
			(layer "F.CrtYd")
		)
		(fp_rect
			(start -0.2794 0.6477)
			(end 0.2794 -0.6477)
			(stroke
				(width 0)
				(type default)
			)
			(fill no)
			(layer "F.Fab")
		)
		(pad "1" smd custom
			(at 0 -0.2794 90)
			(size 0.0762 0.0762)
			(layers "F.Cu" "F.Mask" "F.Paste")
			(net "SAS_HDD_RX_P28")
			(options
				(clearance outline)
				(anchor circle)
			)
			(primitives
				(gr_poly
					(pts
						(arc
							(start 0.1524 -0.127)
							(mid 0.137521 -0.162921)
							(end 0.1016 -0.1778)
						)
						(arc
							(start -0.1016 -0.1778)
							(mid -0.137521 -0.162921)
							(end -0.1524 -0.127)
						)
						(arc
							(start -0.1524 0.127)
							(mid -0.137521 0.162921)
							(end -0.1016 0.1778)
						)
						(arc
							(start 0.1016 0.1778)
							(mid 0.137521 0.162921)
							(end 0.1524 0.127)
						)
					)
					(width 0)
					(fill yes)
				)
			)
		)
		(pad "2" smd custom
			(at 0 0.2794 90)
			(size 0.0762 0.0762)
			(layers "F.Cu" "F.Mask" "F.Paste")
			(net "PHY_SCC_A_TO_DRV_A_28_DP")
			(options
				(clearance outline)
				(anchor circle)
			)
			(primitives
				(gr_poly
					(pts
						(arc
							(start 0.1524 -0.127)
							(mid 0.137521 -0.162921)
							(end 0.1016 -0.1778)
						)
						(arc
							(start -0.1016 -0.1778)
							(mid -0.137521 -0.162921)
							(end -0.1524 -0.127)
						)
						(arc
							(start -0.1524 0.127)
							(mid -0.137521 0.162921)
							(end -0.1016 0.1778)
						)
						(arc
							(start 0.1016 0.1778)
							(mid 0.137521 0.162921)
							(end 0.1524 0.127)
						)
					)
					(width 0)
					(fill yes)
				)
			)
		)
	)
	(footprint ""
		(layer "F.Cu")
		(at 146.249898 -291.000942 -90)
		(property "Reference" "C93"
			(at 0 0 270)
			(layer "F.SilkS")
			(hide yes)
			(effects
				(font
					(size 1.27 1.27)
				)
			)
		)
		(property "Value" "SC10U16V6KX-2GP"
			(at -0.0762 -5.1308 270)
			(unlocked yes)
			(layer "F.Fab")
			(hide yes)
			(effects
				(font
					(size 1.016 1.016)
					(thickness 0.1524)
				)
			)
		)
		(property "Device Type" "C1206H71"
			(at -0.127 -6.6548 270)
			(unlocked yes)
			(layer "F.Fab")
			(hide yes)
			(effects
				(font
					(size 1.016 1.016)
					(thickness 0.1524)
				)
			)
		)
		(duplicate_pad_numbers_are_jumpers no)
		(fp_line
			(start -1.016 2.2352)
			(end -1.016 0.8382)
			(stroke
				(width 0.1524)
				(type default)
			)
			(layer "F.SilkS")
		)
		(fp_line
			(start 1.016 2.2352)
			(end -1.016 2.2352)
			(stroke
				(width 0.1524)
				(type default)
			)
			(layer "F.SilkS")
		)
		(fp_line
			(start 1.016 0.8382)
			(end 1.016 2.2352)
			(stroke
				(width 0.1524)
				(type default)
			)
			(layer "F.SilkS")
		)
		(fp_line
			(start -1.016 -0.8382)
			(end -1.016 -2.2352)
			(stroke
				(width 0.1524)
				(type default)
			)
			(layer "F.SilkS")
		)
		(fp_line
			(start -1.016 -2.2352)
			(end 1.016 -2.2352)
			(stroke
				(width 0.1524)
				(type default)
			)
			(layer "F.SilkS")
		)
		(fp_line
			(start 1.016 -2.2352)
			(end 1.016 -0.8382)
			(stroke
				(width 0.1524)
				(type default)
			)
			(layer "F.SilkS")
		)
		(fp_rect
			(start -1.0922 2.3114)
			(end 1.0922 -2.3114)
			(stroke
				(width 0)
				(type default)
			)
			(fill no)
			(layer "F.CrtYd")
		)
		(fp_poly
			(pts
				(xy 1.0922 -2.3114) (xy 1.0922 2.3114) (xy -1.0922 2.3114) (xy -1.0922 -2.3114)
			)
			(stroke
				(width 0)
				(type default)
			)
			(fill no)
			(layer "F.Fab")
		)
		(pad "1" smd rect
			(at 0 -1.397 270)
			(size 1.651 1.27)
			(layers "F.Cu" "F.Mask" "F.Paste")
			(net "P5V_HDD4")
		)
		(pad "2" smd rect
			(at 0 1.397 270)
			(size 1.651 1.27)
			(layers "F.Cu" "F.Mask" "F.Paste")
			(net "GND")
		)
	)
	(footprint ""
		(layer "F.Cu")
		(at 244.348 -395.9098 180)
		(property "Reference" "R1161"
			(at 0 0 180)
			(layer "F.SilkS")
			(hide yes)
			(effects
				(font
					(size 1.27 1.27)
				)
			)
		)
		(property "Value" "21KR2F-GP"
			(at 0.064008 -3.993896 180)
			(unlocked yes)
			(layer "F.Fab")
			(hide yes)
			(effects
				(font
					(size 1.016 1.016)
					(thickness 0.1524)
				)
			)
		)
		(property "Device Type" "R402H16"
			(at 0.064008 -5.517896 180)
			(unlocked yes)
			(layer "F.Fab")
			(hide yes)
			(effects
				(font
					(size 1.016 1.016)
					(thickness 0.1524)
				)
			)
		)
		(duplicate_pad_numbers_are_jumpers no)
		(fp_line
			(start 0.508 -0.9398)
			(end -0.508 -0.9398)
			(stroke
				(width 0.1524)
				(type default)
			)
			(layer "F.SilkS")
		)
		(fp_line
			(start -0.508 -0.9398)
			(end -0.508 0.9398)
			(stroke
				(width 0.1524)
				(type default)
			)
			(layer "F.SilkS")
		)
		(fp_rect
			(start -0.508 0.9398)
			(end 0.508 -0.9398)
			(stroke
				(width 0)
				(type default)
			)
			(fill no)
			(layer "F.CrtYd")
		)
		(fp_rect
			(start -0.508 0.9398)
			(end 0.508 -0.9398)
			(stroke
				(width 0)
				(type default)
			)
			(fill no)
			(layer "F.Fab")
		)
		(pad "1" smd custom
			(at 0 -0.4445 180)
			(size 0.1397 0.1397)
			(layers "F.Cu" "F.Mask" "F.Paste")
			(net "MB3_PSET_R")
			(options
				(clearance outline)
				(anchor circle)
			)
			(primitives
				(gr_poly
					(pts
						(arc
							(start -0.1778 -0.2794)
							(mid -0.249642 -0.249642)
							(end -0.2794 -0.1778)
						)
						(arc
							(start -0.2794 0.1778)
							(mid -0.249642 0.249642)
							(end -0.1778 0.2794)
						)
						(arc
							(start 0.1778 0.2794)
							(mid 0.249642 0.249642)
							(end 0.2794 0.1778)
						)
						(arc
							(start 0.2794 -0.1778)
							(mid 0.249642 -0.249642)
							(end 0.1778 -0.2794)
						)
					)
					(width 0)
					(fill yes)
				)
			)
		)
		(pad "2" smd custom
			(at 0 0.4445 180)
			(size 0.1397 0.1397)
			(layers "F.Cu" "F.Mask" "F.Paste")
			(net "AGND_CURRENT_DPB")
			(options
				(clearance outline)
				(anchor circle)
			)
			(primitives
				(gr_poly
					(pts
						(arc
							(start -0.1778 -0.2794)
							(mid -0.249642 -0.249642)
							(end -0.2794 -0.1778)
						)
						(arc
							(start -0.2794 0.1778)
							(mid -0.249642 0.249642)
							(end -0.1778 0.2794)
						)
						(arc
							(start 0.1778 0.2794)
							(mid 0.249642 0.249642)
							(end 0.2794 0.1778)
						)
						(arc
							(start 0.2794 -0.1778)
							(mid 0.249642 -0.249642)
							(end 0.1778 -0.2794)
						)
					)
					(width 0)
					(fill yes)
				)
			)
		)
	)
	(footprint ""
		(layer "F.Cu")
		(at 469.942926 -174.857918)
		(property "Reference" "Q140"
			(at 0 0 0)
			(layer "F.SilkS")
			(hide yes)
			(effects
				(font
					(size 1.27 1.27)
				)
			)
		)
		(property "Value" "AO4407AL-GP"
			(at -3.707384 -1.5367 0)
			(unlocked yes)
			(layer "F.Fab")
			(hide yes)
			(effects
				(font
					(size 1.016 1.016)
					(thickness 0.1524)
				)
			)
		)
		(property "Device Type" "SOIC8H69"
			(at -3.707384 -3.0607 0)
			(unlocked yes)
			(layer "F.Fab")
			(hide yes)
			(effects
				(font
					(size 1.016 1.016)
					(thickness 0.1524)
				)
			)
		)
		(duplicate_pad_numbers_are_jumpers no)
		(fp_line
			(start -2.7432 -1.4224)
			(end -2.7432 1.4224)
			(stroke
				(width 0.1524)
				(type default)
			)
			(layer "F.SilkS")
		)
		(fp_line
			(start -2.7432 1.4224)
			(end -2.6416 1.4224)
			(stroke
				(width 0.1524)
				(type default)
			)
			(layer "F.SilkS")
		)
		(fp_line
			(start -2.7432 1.4224)
			(end 2.1336 1.4224)
			(stroke
				(width 0.1524)
				(type default)
			)
			(layer "F.SilkS")
		)
		(fp_line
			(start -2.7178 -0.508)
			(end -2.1844 -0.0508)
			(stroke
				(width 0.1524)
				(type default)
			)
			(layer "F.SilkS")
		)
		(fp_line
			(start -2.6289 3.4417)
			(end -2.6289 1.4732)
			(stroke
				(width 0.381)
				(type default)
			)
			(layer "F.SilkS")
		)
		(fp_line
			(start -2.1844 -0.0508)
			(end -2.7178 0.508)
			(stroke
				(width 0.1524)
				(type default)
			)
			(layer "F.SilkS")
		)
		(fp_line
			(start 2.1336 -1.4224)
			(end -2.7432 -1.4224)
			(stroke
				(width 0.1524)
				(type default)
			)
			(layer "F.SilkS")
		)
		(fp_line
			(start 2.1336 1.4224)
			(end 2.1336 -1.4224)
			(stroke
				(width 0.1524)
				(type default)
			)
			(layer "F.SilkS")
		)
		(fp_poly
			(pts
				(xy -2.2098 -1.4224) (xy -2.2098 1.4224) (xy 2.2098 1.4224) (xy 2.2098 -1.4224)
			)
			(stroke
				(width 0)
				(type default)
			)
			(fill yes)
			(layer "F.SilkS")
		)
		(fp_rect
			(start -2.450084 2.999994)
			(end 2.450084 -2.999994)
			(stroke
				(width 0)
				(type default)
			)
			(fill no)
			(layer "F.CrtYd")
		)
		(fp_poly
			(pts
				(xy -2.8194 3.6322) (xy -2.8194 -3.6322) (xy 2.8194 -3.6322) (xy 2.8194 1.18364) (xy 2.450084 1.18364)
				(xy 2.450084 -2.999994) (xy -2.450084 -2.999994) (xy -2.450084 2.999994) (xy 2.450084 2.999994)
				(xy 2.450084 1.18618) (xy 2.8194 1.18618) (xy 2.8194 3.6322)
			)
			(stroke
				(width 0)
				(type default)
			)
			(fill no)
			(layer "F.CrtYd")
		)
		(fp_rect
			(start -2.8194 3.6322)
			(end 2.8194 -3.6322)
			(stroke
				(width 0)
				(type default)
			)
			(fill no)
			(layer "F.Fab")
		)
		(pad "1" smd rect
			(at -1.905 2.54)
			(size 0.635 1.651)
			(layers "F.Cu" "F.Mask" "F.Paste")
			(net "P12V_A")
		)
		(pad "2" smd rect
			(at -0.635 2.54)
			(size 0.635 1.651)
			(layers "F.Cu" "F.Mask" "F.Paste")
			(net "P12V_A")
		)
		(pad "3" smd rect
			(at 0.635 2.54)
			(size 0.635 1.651)
			(layers "F.Cu" "F.Mask" "F.Paste")
			(net "P12V_A")
		)
		(pad "4" smd rect
			(at 1.905 2.54)
			(size 0.635 1.651)
			(layers "F.Cu" "F.Mask" "F.Paste")
			(net "SW_HDD_N23")
		)
		(pad "5" smd rect
			(at 1.905 -2.54)
			(size 0.635 1.651)
			(layers "F.Cu" "F.Mask" "F.Paste")
			(net "P12V_HDD23")
		)
		(pad "6" smd rect
			(at 0.635 -2.54)
			(size 0.635 1.651)
			(layers "F.Cu" "F.Mask" "F.Paste")
			(net "P12V_HDD23")
		)
		(pad "7" smd rect
			(at -0.635 -2.54)
			(size 0.635 1.651)
			(layers "F.Cu" "F.Mask" "F.Paste")
			(net "P12V_HDD23")
		)
		(pad "8" smd rect
			(at -1.905 -2.54)
			(size 0.635 1.651)
			(layers "F.Cu" "F.Mask" "F.Paste")
			(net "P12V_HDD23")
		)
	)
)
